(kicad_pcb
	(version 20241229)
	(generator "pcbnew")
	(generator_version "9.0")
	(general
		(thickness 1.61)
		(legacy_teardrops no)
	)
	(paper "A3")
	(title_block
		(title "RDIMM DDR5 Tester")
		(date "2026-05-21")
		(rev "2.2.0")
		(company "Antmicro")
		(comment 9 "footprints 299-303 of 796")
	)
	(layers
		(0 "F.Cu" signal)
		(4 "In1.Cu" power)
		(6 "In2.Cu" mixed)
		(8 "In3.Cu" power)
		(10 "In4.Cu" mixed)
		(12 "In5.Cu" power)
		(14 "In6.Cu" mixed)
		(16 "In7.Cu" power)
		(18 "In8.Cu" power)
		(20 "In9.Cu" mixed)
		(22 "In10.Cu" power)
		(2 "B.Cu" signal)
		(9 "F.Adhes" user "F.Adhesive")
		(11 "B.Adhes" user "B.Adhesive")
		(13 "F.Paste" user)
		(15 "B.Paste" user)
		(5 "F.SilkS" user "F.Silkscreen")
		(7 "B.SilkS" user "B.Silkscreen")
		(1 "F.Mask" user)
		(3 "B.Mask" user)
		(17 "Dwgs.User" user "User.Drawings")
		(19 "Cmts.User" user "User.Comments")
		(21 "Eco1.User" user "User.Eco1")
		(23 "Eco2.User" user "User.Eco2")
		(25 "Edge.Cuts" user)
		(27 "Margin" user)
		(31 "F.CrtYd" user "F.Courtyard")
		(29 "B.CrtYd" user "B.Courtyard")
		(35 "F.Fab" user)
		(33 "B.Fab" user)
	)
	(footprint "antmicro-footprints:LED_0603_1608Metric_G"
		(layer "F.Cu")
		(at 110.706 102.224 90)
		(descr "LED SMD 0603 Green")
		(tags "LED SMD 0603 Green")
		(property "Reference" "D5"
			(at -2.575 -0.305 90)
			(layer "F.SilkS")
			(hide yes)
			(effects
				(font
					(size 0.7 0.7)
					(thickness 0.15)
				)
				(justify left bottom)
			)
		)
		(property "Value" "LED_G_0603_KP-1608CGCK"
			(at -0.001 1.599 90)
			(layer "F.Fab")
			(effects
				(font
					(size 0.7 0.7)
					(thickness 0.15)
				)
				(justify left bottom)
			)
		)
		(property "Datasheet" "http://www.kingbright.com/attachments/file/psearch//000/00/00/KP-1608CGCK(Ver.23B).pdf"
			(at 0 0 90)
			(layer "F.Fab")
			(hide yes)
			(effects
				(font
					(size 1.27 1.27)
					(thickness 0.15)
				)
			)
		)
		(property "MPN" "KP-1608CGCK"
			(at 0 0 90)
			(unlocked yes)
			(layer "F.Fab")
			(hide yes)
			(effects
				(font
					(size 1 1)
					(thickness 0.15)
				)
			)
		)
		(property "Manufacturer" "Kingbright"
			(at 0 0 90)
			(unlocked yes)
			(layer "F.Fab")
			(hide yes)
			(effects
				(font
					(size 1 1)
					(thickness 0.15)
				)
			)
		)
		(property "Author" "Antmicro"
			(at 0 0 90)
			(unlocked yes)
			(layer "F.Fab")
			(hide yes)
			(effects
				(font
					(size 1 1)
					(thickness 0.15)
				)
			)
		)
		(property "License" "Apache-2.0"
			(at 0 0 90)
			(unlocked yes)
			(layer "F.Fab")
			(hide yes)
			(effects
				(font
					(size 1 1)
					(thickness 0.15)
				)
			)
		)
		(property "Color" "Green"
			(at 0 0 90)
			(unlocked yes)
			(layer "F.Fab")
			(hide yes)
			(effects
				(font
					(size 1 1)
					(thickness 0.15)
				)
			)
		)
		(sheetname "/FPGA banks HD/")
		(sheetfile "fpga-hd-banks.kicad_sch")
		(attr smd)
		(fp_line
			(start 0.22 -0.35)
			(end -0.22 -0.35)
			(stroke
				(width 0.15)
				(type solid)
			)
			(layer "F.SilkS")
		)
		(fp_line
			(start -1.18 -0.319)
			(end -1.18 0.321)
			(stroke
				(width 0.15)
				(type solid)
			)
			(layer "F.SilkS")
		)
		(fp_line
			(start 0.105328 0.001008)
			(end 0.24 0.001)
			(stroke
				(width 0.1)
				(type solid)
			)
			(layer "F.SilkS")
		)
		(fp_line
			(start -0.094672 0.001008)
			(end 0.105328 -0.198992)
			(stroke
				(width 0.1)
				(type solid)
			)
			(layer "F.SilkS")
		)
		(fp_line
			(start -0.094672 0.001008)
			(end -0.24 0.001008)
			(stroke
				(width 0.1)
				(type solid)
			)
			(layer "F.SilkS")
		)
		(fp_line
			(start 0.105328 0.201008)
			(end 0.105328 -0.198992)
			(stroke
				(width 0.1)
				(type solid)
			)
			(layer "F.SilkS")
		)
		(fp_line
			(start 0.105328 0.201008)
			(end -0.094672 0.001008)
			(stroke
				(width 0.1)
				(type solid)
			)
			(layer "F.SilkS")
		)
		(fp_line
			(start -0.094672 0.201008)
			(end -0.094672 -0.198992)
			(stroke
				(width 0.1)
				(type solid)
			)
			(layer "F.SilkS")
		)
		(fp_line
			(start 0.22 0.35)
			(end -0.22 0.35)
			(stroke
				(width 0.15)
				(type solid)
			)
			(layer "F.SilkS")
		)
		(fp_rect
			(start 1.25 0.65)
			(end -1.25 -0.65)
			(stroke
				(width 0.05)
				(type solid)
			)
			(fill no)
			(layer "F.CrtYd")
		)
		(fp_line
			(start 0.201 -0.202)
			(end -0.101 0)
			(stroke
				(width 0.15)
				(type solid)
			)
			(layer "F.Fab")
		)
		(fp_line
			(start -0.199 -0.202)
			(end -0.199 0.1)
			(stroke
				(width 0.15)
				(type solid)
			)
			(layer "F.Fab")
		)
		(fp_line
			(start 0.599 0)
			(end 0.201 0)
			(stroke
				(width 0.15)
				(type solid)
			)
			(layer "F.Fab")
		)
		(fp_line
			(start 0.201 0)
			(end 0.201 -0.202)
			(stroke
				(width 0.15)
				(type solid)
			)
			(layer "F.Fab")
		)
		(fp_line
			(start -0.101 0)
			(end 0.201 0.2)
			(stroke
				(width 0.15)
				(type solid)
			)
			(layer "F.Fab")
		)
		(fp_line
			(start -0.199 0)
			(end -0.597 0)
			(stroke
				(width 0.15)
				(type solid)
			)
			(layer "F.Fab")
		)
		(fp_line
			(start 0.201 0.2)
			(end 0.201 0)
			(stroke
				(width 0.15)
				(type solid)
			)
			(layer "F.Fab")
		)
		(fp_line
			(start -0.199 0.2)
			(end -0.199 0.1)
			(stroke
				(width 0.15)
				(type solid)
			)
			(layer "F.Fab")
		)
		(fp_rect
			(start 0.848 0.4)
			(end -0.85 -0.402)
			(stroke
				(width 0.15)
				(type solid)
			)
			(fill no)
			(layer "F.Fab")
		)
		(fp_text user "${REFERENCE}"
			(at -1.4224 5.999 90)
			(layer "F.Fab")
			(effects
				(font
					(size 0.7 0.7)
					(thickness 0.15)
				)
				(justify left bottom)
			)
		)
		(fp_text user "License: Apache-2.0"
			(at -1.4224 3.599 90)
			(layer "F.Fab")
			(effects
				(font
					(size 0.7 0.7)
					(thickness 0.15)
				)
				(justify left bottom)
			)
		)
		(fp_text user "Author: Antmicro"
			(at -1.4224 4.799 90)
			(layer "F.Fab")
			(effects
				(font
					(size 0.7 0.7)
					(thickness 0.15)
				)
				(justify left bottom)
			)
		)
		(pad "1" smd roundrect
			(at -0.7 0 270)
			(size 0.8 1)
			(layers "F.Cu" "F.Mask" "F.Paste")
			(roundrect_rratio 0.2)
			(net 151 "+3V3")
			(pinfunction "C")
			(pintype "passive")
		)
		(pad "2" smd roundrect
			(at 0.7 0 270)
			(size 0.8 1)
			(layers "F.Cu" "F.Mask" "F.Paste")
			(roundrect_rratio 0.2)
			(net 230 "Net-(D5-A)")
			(pinfunction "A")
			(pintype "passive")
		)
	)
	(footprint "antmicro-footprints:R_0402_1005Metric"
		(layer "F.Cu")
		(at 144.774499 169.899 -90)
		(descr "Resistor SMD 0402")
		(tags "resistor SMD 0402")
		(property "Reference" "R91"
			(at 1.001 0.974499 90)
			(layer "F.SilkS")
			(effects
				(font
					(size 0.7 0.7)
					(thickness 0.15)
				)
				(justify right bottom)
			)
		)
		(property "Value" "R_0R_0402"
			(at -1.011843 1.772047 90)
			(layer "F.Fab")
			(effects
				(font
					(size 0.7 0.7)
					(thickness 0.15)
				)
				(justify right bottom)
			)
		)
		(property "Datasheet" "https://industrial.panasonic.com/cdbs/www-data/pdf/RDA0000/AOA0000C301.pdf"
			(at 0 0 270)
			(layer "F.Fab")
			(hide yes)
			(effects
				(font
					(size 1.27 1.27)
					(thickness 0.15)
				)
			)
		)
		(property "Manufacturer" "Panasonic"
			(at 0 0 270)
			(unlocked yes)
			(layer "F.Fab")
			(hide yes)
			(effects
				(font
					(size 1 1)
					(thickness 0.15)
				)
			)
		)
		(property "MPN" "ERJ2GE0R00X"
			(at 0 0 270)
			(unlocked yes)
			(layer "F.Fab")
			(hide yes)
			(effects
				(font
					(size 1 1)
					(thickness 0.15)
				)
			)
		)
		(property "Val" "0R"
			(at 0 0 270)
			(unlocked yes)
			(layer "F.Fab")
			(hide yes)
			(effects
				(font
					(size 1 1)
					(thickness 0.15)
				)
			)
		)
		(property "License" "Apache-2.0"
			(at 0 0 270)
			(unlocked yes)
			(layer "F.Fab")
			(hide yes)
			(effects
				(font
					(size 1 1)
					(thickness 0.15)
				)
			)
		)
		(property "Author" "Antmicro"
			(at 0 0 270)
			(unlocked yes)
			(layer "F.Fab")
			(hide yes)
			(effects
				(font
					(size 1 1)
					(thickness 0.15)
				)
			)
		)
		(property "Tolerance" "~"
			(at 0 0 270)
			(unlocked yes)
			(layer "F.Fab")
			(hide yes)
			(effects
				(font
					(size 1 1)
					(thickness 0.15)
				)
			)
		)
		(property "Current" "1A"
			(at 0 0 270)
			(unlocked yes)
			(layer "F.Fab")
			(hide yes)
			(effects
				(font
					(size 1 1)
					(thickness 0.15)
				)
			)
		)
		(sheetname "/Debug FTDI + VNA/")
		(sheetfile "debug-ftdi.kicad_sch")
		(attr smd exclude_from_bom dnp)
		(fp_rect
			(start -0.925 -0.47)
			(end 0.925 0.47)
			(stroke
				(width 0.05)
				(type default)
			)
			(fill no)
			(layer "F.CrtYd")
		)
		(fp_rect
			(start -0.5 -0.25)
			(end 0.5 0.25)
			(stroke
				(width 0.15)
				(type solid)
			)
			(fill no)
			(layer "F.Fab")
		)
		(fp_text user "License: Apache-2.0"
			(at -0.95 5.169 270)
			(layer "F.Fab")
			(effects
				(font
					(size 0.7 0.7)
					(thickness 0.15)
				)
				(justify left bottom)
			)
		)
		(fp_text user "Author: Antmicro"
			(at -0.95 4.169 270)
			(layer "F.Fab")
			(effects
				(font
					(size 0.7 0.7)
					(thickness 0.15)
				)
				(justify left bottom)
			)
		)
		(fp_text user "${REFERENCE}"
			(at -0.95 3.168 270)
			(layer "F.Fab")
			(effects
				(font
					(size 0.7 0.7)
					(thickness 0.15)
				)
				(justify left bottom)
			)
		)
		(pad "1" smd roundrect
			(at -0.48 0 270)
			(size 0.59 0.64)
			(layers "F.Cu" "F.Mask" "F.Paste")
			(roundrect_rratio 0.25)
			(net 441 "/Debug FTDI + VNA/I2C_EN")
			(pintype "passive")
		)
		(pad "2" smd roundrect
			(at 0.48 0 270)
			(size 0.59 0.64)
			(layers "F.Cu" "F.Mask" "F.Paste")
			(roundrect_rratio 0.25)
			(net 301 "Net-(U13-OE)")
			(pintype "passive")
		)
	)
	(footprint "antmicro-footprints:MP_NPTH_Drill3mm"
		(layer "F.Cu")
		(at 262 103)
		(property "Reference" "MP4"
			(at -10.06 1.28 0)
			(layer "F.SilkS")
			(hide yes)
			(effects
				(font
					(size 0.7 0.7)
					(thickness 0.15)
				)
				(justify left bottom)
			)
		)
		(property "Value" "MP_NPTH_Drill3mm"
			(at -13.52 6.2 0)
			(layer "F.Fab")
			(effects
				(font
					(size 0.7 0.7)
					(thickness 0.15)
				)
				(justify left bottom)
			)
		)
		(sheetfile "data-center-rdimm-ddr5-tester.kicad_sch")
		(attr board_only exclude_from_pos_files exclude_from_bom)
		(fp_circle
			(center 0 0)
			(end 1.6 0)
			(stroke
				(width 0.05)
				(type default)
			)
			(fill no)
			(layer "F.CrtYd")
		)
		(fp_text user "License: Apache-2.0"
			(at 0 7.15 0)
			(layer "F.Fab")
			(effects
				(font
					(size 0.7 0.7)
					(thickness 0.15)
				)
				(justify left bottom)
			)
		)
		(fp_text user "${REFERENCE}"
			(at 0 4.749 0)
			(layer "F.Fab")
			(effects
				(font
					(size 0.7 0.7)
					(thickness 0.15)
				)
				(justify left bottom)
			)
		)
		(fp_text user "Author: Antmicro"
			(at 0 5.95 0)
			(layer "F.Fab")
			(effects
				(font
					(size 0.7 0.7)
					(thickness 0.15)
				)
				(justify left bottom)
			)
		)
		(pad "" np_thru_hole circle
			(at 0 0)
			(size 3 3)
			(drill 3)
			(layers "*.Cu" "*.Mask")
		)
	)
	(footprint "antmicro-footprints:SOT-23-6"
		(layer "F.Cu")
		(at 254.224499 132.714 90)
		(property "Reference" "U22"
			(at -0.835 2.7 90)
			(layer "F.SilkS")
			(effects
				(font
					(size 0.7 0.7)
					(thickness 0.15)
				)
				(justify left bottom)
			)
		)
		(property "Value" "MAX16150A_SOT"
			(at -1.75 2.75 90)
			(layer "F.Fab")
			(effects
				(font
					(size 0.7 0.7)
					(thickness 0.15)
				)
				(justify left bottom)
			)
		)
		(property "Datasheet" "https://datasheets.maximintegrated.com/en/ds/MAX16150.pdf"
			(at 0 0 90)
			(layer "F.Fab")
			(hide yes)
			(effects
				(font
					(size 1.27 1.27)
					(thickness 0.15)
				)
			)
		)
		(property "Manufacturer" "Maxim Integrated Products"
			(at 0 0 90)
			(unlocked yes)
			(layer "F.Fab")
			(hide yes)
			(effects
				(font
					(size 1 1)
					(thickness 0.15)
				)
			)
		)
		(property "MPN" "MAX16150AUT+T"
			(at 0 0 90)
			(unlocked yes)
			(layer "F.Fab")
			(hide yes)
			(effects
				(font
					(size 1 1)
					(thickness 0.15)
				)
			)
		)
		(property "License" "Apache-2.0"
			(at 0 0 90)
			(unlocked yes)
			(layer "F.Fab")
			(hide yes)
			(effects
				(font
					(size 1 1)
					(thickness 0.15)
				)
			)
		)
		(property "Author" "Antmicro"
			(at 0 0 90)
			(unlocked yes)
			(layer "F.Fab")
			(hide yes)
			(effects
				(font
					(size 1 1)
					(thickness 0.15)
				)
			)
		)
		(sheetname "/Supply/")
		(sheetfile "supply.kicad_sch")
		(attr smd)
		(fp_line
			(start 1.45 -0.757)
			(end 1.45 -0.457)
			(stroke
				(width 0.12)
				(type solid)
			)
			(layer "F.SilkS")
		)
		(fp_line
			(start 1.3 -0.757)
			(end 1.45 -0.757)
			(stroke
				(width 0.12)
				(type solid)
			)
			(layer "F.SilkS")
		)
		(fp_line
			(start -1.3 -0.757)
			(end -1.45 -0.757)
			(stroke
				(width 0.12)
				(type solid)
			)
			(layer "F.SilkS")
		)
		(fp_line
			(start -1.45 -0.757)
			(end -1.45 -0.457)
			(stroke
				(width 0.12)
				(type solid)
			)
			(layer "F.SilkS")
		)
		(fp_line
			(start 1.45 0.643)
			(end 1.45 0.343)
			(stroke
				(width 0.12)
				(type solid)
			)
			(layer "F.SilkS")
		)
		(fp_line
			(start 1.3 0.643)
			(end 1.45 0.643)
			(stroke
				(width 0.12)
				(type solid)
			)
			(layer "F.SilkS")
		)
		(fp_line
			(start -1.45 0.643)
			(end -1.45 0.343)
			(stroke
				(width 0.12)
				(type solid)
			)
			(layer "F.SilkS")
		)
		(fp_rect
			(start -1.55 -1.85)
			(end 1.55 1.75)
			(stroke
				(width 0.05)
				(type solid)
			)
			(fill no)
			(layer "F.CrtYd")
		)
		(fp_line
			(start 1.5 -0.757)
			(end 1.5 0.643)
			(stroke
				(width 0.1)
				(type solid)
			)
			(layer "F.Fab")
		)
		(fp_line
			(start -1.5 -0.757)
			(end 1.5 -0.757)
			(stroke
				(width 0.1)
				(type solid)
			)
			(layer "F.Fab")
		)
		(fp_line
			(start 1.5 0.643)
			(end -1.5 0.643)
			(stroke
				(width 0.1)
				(type solid)
			)
			(layer "F.Fab")
		)
		(fp_line
			(start -1.5 0.643)
			(end -1.5 -0.757)
			(stroke
				(width 0.1)
				(type solid)
			)
			(layer "F.Fab")
		)
		(fp_text user "."
			(at -1.4 1.2 90)
			(layer "F.SilkS")
			(effects
				(font
					(size 1 1)
					(thickness 0.15)
				)
			)
		)
		(fp_text user "License: Apache-2.0"
			(at -1.75 6.5 90)
			(layer "F.Fab")
			(effects
				(font
					(size 0.7 0.7)
					(thickness 0.15)
				)
				(justify left bottom)
			)
		)
		(fp_text user "Author: Antmicro"
			(at -1.829 5.25 90)
			(layer "F.Fab")
			(effects
				(font
					(size 0.7 0.7)
					(thickness 0.15)
				)
				(justify left bottom)
			)
		)
		(fp_text user "${REFERENCE}"
			(at -1.75 4 90)
			(layer "F.Fab")
			(effects
				(font
					(size 0.7 0.7)
					(thickness 0.15)
				)
				(justify left bottom)
			)
		)
		(pad "1" smd roundrect
			(at -0.954 1.1 90)
			(size 0.55 1)
			(layers "F.Cu" "F.Mask" "F.Paste")
			(roundrect_rratio 0.15)
			(net 189 "/Supply/~{PB_CTRL_IN}")
			(pinfunction "~{PB_IN}")
			(pintype "input")
		)
		(pad "2" smd roundrect
			(at -0.003 1.1 90)
			(size 0.55 1)
			(layers "F.Cu" "F.Mask" "F.Paste")
			(roundrect_rratio 0.15)
			(net 1 "GND")
			(pinfunction "GND")
			(pintype "power_in")
		)
		(pad "3" smd roundrect
			(at 0.947 1.1 90)
			(size 0.55 1)
			(layers "F.Cu" "F.Mask" "F.Paste")
			(roundrect_rratio 0.15)
			(net 38 "+3V3_AON")
			(pinfunction "VCC")
			(pintype "power_in")
		)
		(pad "4" smd roundrect
			(at 0.947 -1.214 90)
			(size 0.55 1)
			(layers "F.Cu" "F.Mask" "F.Paste")
			(roundrect_rratio 0.15)
			(net 138 "/Supply/PB_CTRL_OUT")
			(pinfunction "OUT")
			(pintype "output")
		)
		(pad "5" smd roundrect
			(at -0.003 -1.214 90)
			(size 0.55 1)
			(layers "F.Cu" "F.Mask" "F.Paste")
			(roundrect_rratio 0.15)
			(net 157 "/Supply/~{PB_CTRL_INT}")
			(pinfunction "~{INT}")
			(pintype "output")
		)
		(pad "6" smd roundrect
			(at -0.954 -1.214 90)
			(size 0.55 1)
			(layers "F.Cu" "F.Mask" "F.Paste")
			(roundrect_rratio 0.15)
			(net 137 "/Supply/~{PB_CTRL_CLR}")
			(pinfunction "~{CLR}")
			(pintype "input")
		)
	)
	(footprint "antmicro-footprints:TP_1206_SMD_RCW-0C"
		(layer "F.Cu")
		(at 262.424499 178.449 90)
		(property "Reference" "TP20"
			(at -2.29 -1.4 90)
			(layer "F.SilkS")
			(hide yes)
			(effects
				(font
					(size 0.7 0.7)
					(thickness 0.15)
				)
				(justify left bottom)
			)
		)
		(property "Value" "TP_1206_SMD_RCW-0C"
			(at -4.68 2.25 90)
			(layer "F.Fab")
			(effects
				(font
					(size 0.7 0.7)
					(thickness 0.15)
				)
				(justify left bottom)
			)
		)
		(property "Datasheet" "https://www.te.com/commerce/DocumentDelivery/DDEController?Action=srchrtrv&DocNm=1773266&DocType=DS&DocLang=English"
			(at 0 0 90)
			(layer "F.Fab")
			(hide yes)
			(effects
				(font
					(size 1.27 1.27)
					(thickness 0.15)
				)
			)
		)
		(property "MPN" "RCW-0C"
			(at 0 0 90)
			(unlocked yes)
			(layer "F.Fab")
			(hide yes)
			(effects
				(font
					(size 1 1)
					(thickness 0.15)
				)
			)
		)
		(property "Manufacturer" "TE Connectivity"
			(at 0 0 90)
			(unlocked yes)
			(layer "F.Fab")
			(hide yes)
			(effects
				(font
					(size 1 1)
					(thickness 0.15)
				)
			)
		)
		(property "Author" "Antmicro"
			(at 0 0 90)
			(unlocked yes)
			(layer "F.Fab")
			(hide yes)
			(effects
				(font
					(size 1 1)
					(thickness 0.15)
				)
			)
		)
		(property "License" "Apache-2.0"
			(at 0 0 90)
			(unlocked yes)
			(layer "F.Fab")
			(hide yes)
			(effects
				(font
					(size 1 1)
					(thickness 0.15)
				)
			)
		)
		(sheetname "/Supply/")
		(sheetfile "supply.kicad_sch")
		(attr smd)
		(fp_line
			(start 1.78 -0.981)
			(end 1.281 -0.981)
			(stroke
				(width 0.15)
				(type solid)
			)
			(layer "F.SilkS")
		)
		(fp_line
			(start 1.78 -0.981)
			(end 1.78 -0.479)
			(stroke
				(width 0.15)
				(type solid)
			)
			(layer "F.SilkS")
		)
		(fp_line
			(start -1.779 -0.981)
			(end -1.279 -0.981)
			(stroke
				(width 0.15)
				(type solid)
			)
			(layer "F.SilkS")
		)
		(fp_line
			(start -1.779 -0.981)
			(end -1.779 -0.479)
			(stroke
				(width 0.15)
				(type solid)
			)
			(layer "F.SilkS")
		)
		(fp_line
			(start -1.779 0.482)
			(end -1.779 0.98)
			(stroke
				(width 0.15)
				(type solid)
			)
			(layer "F.SilkS")
		)
		(fp_line
			(start -1.779 0.98)
			(end -1.279 0.98)
			(stroke
				(width 0.15)
				(type solid)
			)
			(layer "F.SilkS")
		)
		(fp_line
			(start 1.78 0.982)
			(end 1.78 0.482)
			(stroke
				(width 0.15)
				(type solid)
			)
			(layer "F.SilkS")
		)
		(fp_line
			(start 1.78 0.982)
			(end 1.281 0.982)
			(stroke
				(width 0.15)
				(type solid)
			)
			(layer "F.SilkS")
		)
		(fp_rect
			(start -2.101 -1.314)
			(end 2.1 1.312)
			(stroke
				(width 0.05)
				(type solid)
			)
			(fill no)
			(layer "F.CrtYd")
		)
		(fp_rect
			(start -1.601 -0.814)
			(end 1.6 0.812)
			(stroke
				(width 0.15)
				(type solid)
			)
			(fill no)
			(layer "F.Fab")
		)
		(fp_text user "Author: Antmicro"
			(at -4.68 4.25 90)
			(layer "F.Fab")
			(effects
				(font
					(size 0.7 0.7)
					(thickness 0.15)
				)
				(justify left bottom)
			)
		)
		(fp_text user "${REFERENCE}"
			(at -4.68 6.65 90)
			(layer "F.Fab")
			(effects
				(font
					(size 0.7 0.7)
					(thickness 0.15)
				)
				(justify left bottom)
			)
		)
		(fp_text user "License: Apache-2.0"
			(at -4.68 5.45 90)
			(layer "F.Fab")
			(effects
				(font
					(size 0.7 0.7)
					(thickness 0.15)
				)
				(justify left bottom)
			)
		)
		(pad "1" smd rect
			(at 0 0 90)
			(size 3.4 1.8)
			(layers "F.Cu" "F.Mask" "F.Paste")
			(net 1 "GND")
			(pinfunction "1")
			(pintype "passive")
		)
	)
)
